(kicad_pcb
	(version 20260206)
	(generator "pcbnew")
	(generator_version "10.0")
	(general
		(thickness 1.6)
		(legacy_teardrops no)
	)
	(paper "A4")
	(title_block
		(title "01162023_DA0F0TEBIF0_F0T_Expander_BD_F_brd_V02_OCP.brd")
		(comment 1 "Grand Teton / footprints 8135-8142 of 9728")
	)
	(layers
		(0 "F.Cu" signal "TOP")
		(4 "In1.Cu" signal "GND")
		(6 "In2.Cu" signal "VCC")
		(8 "In3.Cu" signal "VCC1")
		(10 "In4.Cu" signal "GND1")
		(12 "In5.Cu" signal "IN1")
		(14 "In6.Cu" signal "GND2")
		(16 "In7.Cu" signal "IN2")
		(18 "In8.Cu" signal "GND3")
		(20 "In9.Cu" signal "IN3")
		(22 "In10.Cu" signal "GND4")
		(24 "In11.Cu" signal "IN4")
		(26 "In12.Cu" signal "GND5")
		(28 "In13.Cu" signal "IN5")
		(30 "In14.Cu" signal "GND6")
		(32 "In15.Cu" signal "IN6")
		(34 "In16.Cu" signal "GND7")
		(2 "B.Cu" signal "BOTTOM")
		(9 "F.Adhes" user "F.Adhesive")
		(11 "B.Adhes" user "B.Adhesive")
		(13 "F.Paste" user "Package Geometry/Pastemask Top")
		(15 "B.Paste" user "Package Geometry/Pastemask Bottom")
		(5 "F.SilkS" user "Ref Des/Silkscreen Top")
		(7 "B.SilkS" user "Ref Des/Silkscreen Bottom")
		(1 "F.Mask" user "Board Geometry/Soldermask Top")
		(3 "B.Mask" user "Board Geometry/Soldermask Bottom")
		(17 "Dwgs.User" user "User.Drawings")
		(19 "Cmts.User" user "User.Comments")
		(21 "Eco1.User" user "User.Eco1")
		(23 "Eco2.User" user "User.Eco2")
		(25 "Edge.Cuts" user "Board Geometry/Outline")
		(27 "Margin" user)
		(31 "F.CrtYd" user "Package Geometry/Place Bound Top")
		(29 "B.CrtYd" user "Package Geometry/Place Bound Bottom")
		(35 "F.Fab" user "Ref Des/Assembly Top")
		(33 "B.Fab" user "Ref Des/Assembly Bottom")
	)
	(footprint ""
		(layer "B.Cu")
		(at 351.916238 -324.950582 -90)
		(property "Reference" "C4366"
			(at 0 0 90)
			(layer "B.SilkS")
			(hide yes)
			(effects
				(font
					(size 1.27 1.27)
				)
				(justify mirror)
			)
		)
		(property "Value" ""
			(at 0 0 90)
			(layer "B.Fab")
			(effects
				(font
					(size 1.27 1.27)
				)
				(justify mirror)
			)
		)
		(duplicate_pad_numbers_are_jumpers no)
		(fp_line
			(start -1.2954 0.5842)
			(end 1.2954 0.5842)
			(stroke
				(width 0.1524)
				(type default)
			)
			(layer "B.SilkS")
		)
		(fp_line
			(start 1.2954 0.5842)
			(end 1.2954 -0.5842)
			(stroke
				(width 0.1524)
				(type default)
			)
			(layer "B.SilkS")
		)
		(fp_line
			(start -1.2954 -0.5842)
			(end -1.2954 0.5842)
			(stroke
				(width 0.1524)
				(type default)
			)
			(layer "B.SilkS")
		)
		(fp_line
			(start 1.2954 -0.5842)
			(end -1.2954 -0.5842)
			(stroke
				(width 0.1524)
				(type default)
			)
			(layer "B.SilkS")
		)
		(fp_line
			(start -0.8636 0.4572)
			(end 0.8636 0.4572)
			(stroke
				(width 0.1)
				(type default)
			)
			(layer "B.Fab")
		)
		(fp_line
			(start 0.8636 0.4572)
			(end 0.8636 0.4064)
			(stroke
				(width 0.1)
				(type default)
			)
			(layer "B.Fab")
		)
		(fp_line
			(start -1.1938 0.4064)
			(end -0.8636 0.4064)
			(stroke
				(width 0.1)
				(type default)
			)
			(layer "B.Fab")
		)
		(fp_line
			(start -0.8636 0.4064)
			(end -0.8636 0.4572)
			(stroke
				(width 0.1)
				(type default)
			)
			(layer "B.Fab")
		)
		(fp_line
			(start 0.8636 0.4064)
			(end 1.1938 0.4064)
			(stroke
				(width 0.1)
				(type default)
			)
			(layer "B.Fab")
		)
		(fp_line
			(start 1.1938 0.4064)
			(end 1.1938 -0.4064)
			(stroke
				(width 0.1)
				(type default)
			)
			(layer "B.Fab")
		)
		(fp_line
			(start -1.1938 -0.4064)
			(end -1.1938 0.4064)
			(stroke
				(width 0.1)
				(type default)
			)
			(layer "B.Fab")
		)
		(fp_line
			(start -0.8636 -0.4064)
			(end -1.1938 -0.4064)
			(stroke
				(width 0.1)
				(type default)
			)
			(layer "B.Fab")
		)
		(fp_line
			(start 0.8636 -0.4064)
			(end 0.8636 -0.4572)
			(stroke
				(width 0.1)
				(type default)
			)
			(layer "B.Fab")
		)
		(fp_line
			(start 1.1938 -0.4064)
			(end 0.8636 -0.4064)
			(stroke
				(width 0.1)
				(type default)
			)
			(layer "B.Fab")
		)
		(fp_line
			(start -0.8636 -0.4572)
			(end -0.8636 -0.4064)
			(stroke
				(width 0.1)
				(type default)
			)
			(layer "B.Fab")
		)
		(fp_line
			(start 0.8636 -0.4572)
			(end -0.8636 -0.4572)
			(stroke
				(width 0.1)
				(type default)
			)
			(layer "B.Fab")
		)
		(pad "1" smd rect
			(at 0.7366 0 180)
			(size 0.7112 0.8128)
			(layers "B.Cu" "B.Mask" "B.Paste")
			(net "P0V8_SERDES_VDDA_PEX3_C0")
		)
		(pad "2" smd rect
			(at -0.7366 0 180)
			(size 0.7112 0.8128)
			(layers "B.Cu" "B.Mask" "B.Paste")
			(net "GND")
		)
	)
	(footprint ""
		(layer "B.Cu")
		(at 127.076708 -321.813174 -90)
		(property "Reference" "R6477"
			(at 0 0 90)
			(layer "B.SilkS")
			(hide yes)
			(effects
				(font
					(size 1.27 1.27)
				)
				(justify mirror)
			)
		)
		(property "Value" ""
			(at 0 0 90)
			(layer "B.Fab")
			(effects
				(font
					(size 1.27 1.27)
				)
				(justify mirror)
			)
		)
		(duplicate_pad_numbers_are_jumpers no)
		(fp_line
			(start -0.7874 0.4064)
			(end 0.7874 0.4064)
			(stroke
				(width 0.1524)
				(type default)
			)
			(layer "B.SilkS")
		)
		(fp_line
			(start 0.7874 0.4064)
			(end 0.7874 -0.4064)
			(stroke
				(width 0.1524)
				(type default)
			)
			(layer "B.SilkS")
		)
		(fp_line
			(start -0.7874 -0.4064)
			(end -0.7874 0.4064)
			(stroke
				(width 0.1524)
				(type default)
			)
			(layer "B.SilkS")
		)
		(fp_line
			(start 0.7874 -0.4064)
			(end -0.7874 -0.4064)
			(stroke
				(width 0.1524)
				(type default)
			)
			(layer "B.SilkS")
		)
		(fp_line
			(start -0.67945 0.3048)
			(end -0.120396 0.3048)
			(stroke
				(width 0.1)
				(type default)
			)
			(layer "B.Fab")
		)
		(fp_line
			(start -0.120396 0.3048)
			(end -0.120396 0.2794)
			(stroke
				(width 0.1)
				(type default)
			)
			(layer "B.Fab")
		)
		(fp_line
			(start 0.12065 0.3048)
			(end 0.67945 0.3048)
			(stroke
				(width 0.1)
				(type default)
			)
			(layer "B.Fab")
		)
		(fp_line
			(start 0.67945 0.3048)
			(end 0.67945 -0.305054)
			(stroke
				(width 0.1)
				(type default)
			)
			(layer "B.Fab")
		)
		(fp_line
			(start -0.120396 0.2794)
			(end 0.12065 0.2794)
			(stroke
				(width 0.1)
				(type default)
			)
			(layer "B.Fab")
		)
		(fp_line
			(start 0.12065 0.2794)
			(end 0.12065 0.3048)
			(stroke
				(width 0.1)
				(type default)
			)
			(layer "B.Fab")
		)
		(fp_line
			(start -0.12065 -0.2794)
			(end -0.12065 -0.3048)
			(stroke
				(width 0.1)
				(type default)
			)
			(layer "B.Fab")
		)
		(fp_line
			(start 0.12065 -0.2794)
			(end -0.12065 -0.2794)
			(stroke
				(width 0.1)
				(type default)
			)
			(layer "B.Fab")
		)
		(fp_line
			(start -0.67945 -0.3048)
			(end -0.67945 0.3048)
			(stroke
				(width 0.1)
				(type default)
			)
			(layer "B.Fab")
		)
		(fp_line
			(start -0.12065 -0.3048)
			(end -0.67945 -0.3048)
			(stroke
				(width 0.1)
				(type default)
			)
			(layer "B.Fab")
		)
		(fp_line
			(start 0.12065 -0.305054)
			(end 0.12065 -0.2794)
			(stroke
				(width 0.1)
				(type default)
			)
			(layer "B.Fab")
		)
		(fp_line
			(start 0.67945 -0.305054)
			(end 0.12065 -0.305054)
			(stroke
				(width 0.1)
				(type default)
			)
			(layer "B.Fab")
		)
		(pad "1" smd circle
			(at 0.40005 0 90)
			(size 0 0)
			(layers "B.Cu" "B.Mask" "B.Paste")
			(net "P0V8_SERDES_VDDA_PEX1")
		)
		(pad "2" smd circle
			(at -0.40005 0 90)
			(size 0 0)
			(layers "B.Cu" "B.Mask" "B.Paste")
			(net "P0V8_SERDES_VDDA_PEX1_C2")
		)
	)
	(footprint ""
		(layer "B.Cu")
		(at 353.22637 -308.613556 90)
		(property "Reference" "C1922"
			(at 0 0 90)
			(layer "B.SilkS")
			(hide yes)
			(effects
				(font
					(size 1.27 1.27)
				)
				(justify mirror)
			)
		)
		(property "Value" ""
			(at 0 0 90)
			(layer "B.Fab")
			(effects
				(font
					(size 1.27 1.27)
				)
				(justify mirror)
			)
		)
		(duplicate_pad_numbers_are_jumpers no)
		(fp_line
			(start 1.2954 -0.5842)
			(end -1.2954 -0.5842)
			(stroke
				(width 0.1524)
				(type default)
			)
			(layer "B.SilkS")
		)
		(fp_line
			(start -1.2954 -0.5842)
			(end -1.2954 0.5842)
			(stroke
				(width 0.1524)
				(type default)
			)
			(layer "B.SilkS")
		)
		(fp_line
			(start 1.2954 0.5842)
			(end 1.2954 -0.5842)
			(stroke
				(width 0.1524)
				(type default)
			)
			(layer "B.SilkS")
		)
		(fp_line
			(start -1.2954 0.5842)
			(end 1.2954 0.5842)
			(stroke
				(width 0.1524)
				(type default)
			)
			(layer "B.SilkS")
		)
		(fp_line
			(start 0.8636 -0.4572)
			(end -0.8636 -0.4572)
			(stroke
				(width 0.1)
				(type default)
			)
			(layer "B.Fab")
		)
		(fp_line
			(start -0.8636 -0.4572)
			(end -0.8636 -0.4064)
			(stroke
				(width 0.1)
				(type default)
			)
			(layer "B.Fab")
		)
		(fp_line
			(start 1.1938 -0.4064)
			(end 0.8636 -0.4064)
			(stroke
				(width 0.1)
				(type default)
			)
			(layer "B.Fab")
		)
		(fp_line
			(start 0.8636 -0.4064)
			(end 0.8636 -0.4572)
			(stroke
				(width 0.1)
				(type default)
			)
			(layer "B.Fab")
		)
		(fp_line
			(start -0.8636 -0.4064)
			(end -1.1938 -0.4064)
			(stroke
				(width 0.1)
				(type default)
			)
			(layer "B.Fab")
		)
		(fp_line
			(start -1.1938 -0.4064)
			(end -1.1938 0.4064)
			(stroke
				(width 0.1)
				(type default)
			)
			(layer "B.Fab")
		)
		(fp_line
			(start 1.1938 0.4064)
			(end 1.1938 -0.4064)
			(stroke
				(width 0.1)
				(type default)
			)
			(layer "B.Fab")
		)
		(fp_line
			(start 0.8636 0.4064)
			(end 1.1938 0.4064)
			(stroke
				(width 0.1)
				(type default)
			)
			(layer "B.Fab")
		)
		(fp_line
			(start -0.8636 0.4064)
			(end -0.8636 0.4572)
			(stroke
				(width 0.1)
				(type default)
			)
			(layer "B.Fab")
		)
		(fp_line
			(start -1.1938 0.4064)
			(end -0.8636 0.4064)
			(stroke
				(width 0.1)
				(type default)
			)
			(layer "B.Fab")
		)
		(fp_line
			(start 0.8636 0.4572)
			(end 0.8636 0.4064)
			(stroke
				(width 0.1)
				(type default)
			)
			(layer "B.Fab")
		)
		(fp_line
			(start -0.8636 0.4572)
			(end 0.8636 0.4572)
			(stroke
				(width 0.1)
				(type default)
			)
			(layer "B.Fab")
		)
		(pad "1" smd rect
			(at 0.7366 0)
			(size 0.7112 0.8128)
			(layers "B.Cu" "B.Mask" "B.Paste")
			(net "P0V8_SERDES_VDDA_PEX3")
		)
		(pad "2" smd rect
			(at -0.7366 0)
			(size 0.7112 0.8128)
			(layers "B.Cu" "B.Mask" "B.Paste")
			(net "GND")
		)
	)
	(footprint ""
		(layer "B.Cu")
		(at 176.251362 -305.399948 -90)
		(property "Reference" "C3152"
			(at 0 0 90)
			(layer "B.SilkS")
			(hide yes)
			(effects
				(font
					(size 1.27 1.27)
				)
				(justify mirror)
			)
		)
		(property "Value" ""
			(at 0 0 90)
			(layer "B.Fab")
			(effects
				(font
					(size 1.27 1.27)
				)
				(justify mirror)
			)
		)
		(duplicate_pad_numbers_are_jumpers no)
		(fp_line
			(start -0.299974 0.150114)
			(end 0.299974 0.150114)
			(stroke
				(width 0.1)
				(type default)
			)
			(layer "B.Fab")
		)
		(fp_line
			(start 0.299974 0.150114)
			(end 0.299974 -0.150114)
			(stroke
				(width 0.1)
				(type default)
			)
			(layer "B.Fab")
		)
		(fp_line
			(start -0.299974 -0.150114)
			(end -0.299974 0.150114)
			(stroke
				(width 0.1)
				(type default)
			)
			(layer "B.Fab")
		)
		(fp_line
			(start 0.299974 -0.150114)
			(end -0.299974 -0.150114)
			(stroke
				(width 0.1)
				(type default)
			)
			(layer "B.Fab")
		)
		(pad "1" smd rect
			(at 0.2667 0 90)
			(size 0.3048 0.381)
			(layers "B.Cu" "B.Mask" "B.Paste")
			(net "P1V25_SERDES_VDDPLL_PEX1")
		)
		(pad "2" smd rect
			(at -0.2667 0 90)
			(size 0.3048 0.381)
			(layers "B.Cu" "B.Mask" "B.Paste")
			(net "GND")
		)
	)
	(footprint ""
		(layer "B.Cu")
		(at 182.39994 -301.599854 -90)
		(property "Reference" "C1446"
			(at 0 0 90)
			(layer "B.SilkS")
			(hide yes)
			(effects
				(font
					(size 1.27 1.27)
				)
				(justify mirror)
			)
		)
		(property "Value" ""
			(at 0 0 90)
			(layer "B.Fab")
			(effects
				(font
					(size 1.27 1.27)
				)
				(justify mirror)
			)
		)
		(duplicate_pad_numbers_are_jumpers no)
		(fp_line
			(start -0.299974 0.150114)
			(end 0.299974 0.150114)
			(stroke
				(width 0.1)
				(type default)
			)
			(layer "B.Fab")
		)
		(fp_line
			(start 0.299974 0.150114)
			(end 0.299974 -0.150114)
			(stroke
				(width 0.1)
				(type default)
			)
			(layer "B.Fab")
		)
		(fp_line
			(start -0.299974 -0.150114)
			(end -0.299974 0.150114)
			(stroke
				(width 0.1)
				(type default)
			)
			(layer "B.Fab")
		)
		(fp_line
			(start 0.299974 -0.150114)
			(end -0.299974 -0.150114)
			(stroke
				(width 0.1)
				(type default)
			)
			(layer "B.Fab")
		)
		(pad "1" smd rect
			(at 0.2667 0 90)
			(size 0.3048 0.381)
			(layers "B.Cu" "B.Mask" "B.Paste")
			(net "P0V8_SERDES_VDDA_PEX1")
		)
		(pad "2" smd rect
			(at -0.2667 0 90)
			(size 0.3048 0.381)
			(layers "B.Cu" "B.Mask" "B.Paste")
			(net "GND")
		)
	)
	(footprint ""
		(layer "B.Cu")
		(at 300.872144 -113.437924 180)
		(property "Reference" "R265"
			(at 0 0 0)
			(layer "B.SilkS")
			(hide yes)
			(effects
				(font
					(size 1.27 1.27)
				)
				(justify mirror)
			)
		)
		(property "Value" ""
			(at 0 0 0)
			(layer "B.Fab")
			(effects
				(font
					(size 1.27 1.27)
				)
				(justify mirror)
			)
		)
		(duplicate_pad_numbers_are_jumpers no)
		(fp_line
			(start 0.7874 0.4064)
			(end 0.7874 -0.4064)
			(stroke
				(width 0.1524)
				(type default)
			)
			(layer "B.SilkS")
		)
		(fp_line
			(start 0.7874 -0.4064)
			(end -0.7874 -0.4064)
			(stroke
				(width 0.1524)
				(type default)
			)
			(layer "B.SilkS")
		)
		(fp_line
			(start -0.7874 0.4064)
			(end 0.7874 0.4064)
			(stroke
				(width 0.1524)
				(type default)
			)
			(layer "B.SilkS")
		)
		(fp_line
			(start -0.7874 -0.4064)
			(end -0.7874 0.4064)
			(stroke
				(width 0.1524)
				(type default)
			)
			(layer "B.SilkS")
		)
		(fp_line
			(start 0.67945 0.3048)
			(end 0.67945 -0.305054)
			(stroke
				(width 0.1)
				(type default)
			)
			(layer "B.Fab")
		)
		(fp_line
			(start 0.67945 -0.305054)
			(end 0.12065 -0.305054)
			(stroke
				(width 0.1)
				(type default)
			)
			(layer "B.Fab")
		)
		(fp_line
			(start 0.12065 0.3048)
			(end 0.67945 0.3048)
			(stroke
				(width 0.1)
				(type default)
			)
			(layer "B.Fab")
		)
		(fp_line
			(start 0.12065 0.2794)
			(end 0.12065 0.3048)
			(stroke
				(width 0.1)
				(type default)
			)
			(layer "B.Fab")
		)
		(fp_line
			(start 0.12065 -0.2794)
			(end -0.12065 -0.2794)
			(stroke
				(width 0.1)
				(type default)
			)
			(layer "B.Fab")
		)
		(fp_line
			(start 0.12065 -0.305054)
			(end 0.12065 -0.2794)
			(stroke
				(width 0.1)
				(type default)
			)
			(layer "B.Fab")
		)
		(fp_line
			(start -0.120396 0.3048)
			(end -0.120396 0.2794)
			(stroke
				(width 0.1)
				(type default)
			)
			(layer "B.Fab")
		)
		(fp_line
			(start -0.120396 0.2794)
			(end 0.12065 0.2794)
			(stroke
				(width 0.1)
				(type default)
			)
			(layer "B.Fab")
		)
		(fp_line
			(start -0.12065 -0.2794)
			(end -0.12065 -0.3048)
			(stroke
				(width 0.1)
				(type default)
			)
			(layer "B.Fab")
		)
		(fp_line
			(start -0.12065 -0.3048)
			(end -0.67945 -0.3048)
			(stroke
				(width 0.1)
				(type default)
			)
			(layer "B.Fab")
		)
		(fp_line
			(start -0.67945 0.3048)
			(end -0.120396 0.3048)
			(stroke
				(width 0.1)
				(type default)
			)
			(layer "B.Fab")
		)
		(fp_line
			(start -0.67945 -0.3048)
			(end -0.67945 0.3048)
			(stroke
				(width 0.1)
				(type default)
			)
			(layer "B.Fab")
		)
		(pad "1" smd circle
			(at 0.40005 0)
			(size 0 0)
			(layers "B.Cu" "B.Mask" "B.Paste")
			(net "SMB_NIC5_LS_SDA")
		)
		(pad "2" smd circle
			(at -0.40005 0)
			(size 0 0)
			(layers "B.Cu" "B.Mask" "B.Paste")
			(net "P3V3_NIC5")
		)
	)
	(footprint ""
		(layer "B.Cu")
		(at 165.299898 -290.674806 180)
		(property "Reference" "C1359"
			(at 0 0 0)
			(layer "B.SilkS")
			(hide yes)
			(effects
				(font
					(size 1.27 1.27)
				)
				(justify mirror)
			)
		)
		(property "Value" ""
			(at 0 0 0)
			(layer "B.Fab")
			(effects
				(font
					(size 1.27 1.27)
				)
				(justify mirror)
			)
		)
		(duplicate_pad_numbers_are_jumpers no)
		(fp_line
			(start 0.299974 0.150114)
			(end 0.299974 -0.150114)
			(stroke
				(width 0.1)
				(type default)
			)
			(layer "B.Fab")
		)
		(fp_line
			(start 0.299974 -0.150114)
			(end -0.299974 -0.150114)
			(stroke
				(width 0.1)
				(type default)
			)
			(layer "B.Fab")
		)
		(fp_line
			(start -0.299974 0.150114)
			(end 0.299974 0.150114)
			(stroke
				(width 0.1)
				(type default)
			)
			(layer "B.Fab")
		)
		(fp_line
			(start -0.299974 -0.150114)
			(end -0.299974 0.150114)
			(stroke
				(width 0.1)
				(type default)
			)
			(layer "B.Fab")
		)
		(pad "1" smd rect
			(at 0.2667 0)
			(size 0.3048 0.381)
			(layers "B.Cu" "B.Mask" "B.Paste")
			(net "P0V8_PEX1")
		)
		(pad "2" smd rect
			(at -0.2667 0)
			(size 0.3048 0.381)
			(layers "B.Cu" "B.Mask" "B.Paste")
			(net "GND")
		)
	)
	(footprint ""
		(layer "B.Cu")
		(at 257.531108 -226.52482 -90)
		(property "Reference" "R3487"
			(at 0 0 90)
			(layer "B.SilkS")
			(hide yes)
			(effects
				(font
					(size 1.27 1.27)
				)
				(justify mirror)
			)
		)
		(property "Value" ""
			(at 0 0 90)
			(layer "B.Fab")
			(effects
				(font
					(size 1.27 1.27)
				)
				(justify mirror)
			)
		)
		(duplicate_pad_numbers_are_jumpers no)
		(fp_line
			(start -0.7874 0.4064)
			(end 0.7874 0.4064)
			(stroke
				(width 0.1524)
				(type default)
			)
			(layer "B.SilkS")
		)
		(fp_line
			(start 0.7874 0.4064)
			(end 0.7874 -0.4064)
			(stroke
				(width 0.1524)
				(type default)
			)
			(layer "B.SilkS")
		)
		(fp_line
			(start -0.7874 -0.4064)
			(end -0.7874 0.4064)
			(stroke
				(width 0.1524)
				(type default)
			)
			(layer "B.SilkS")
		)
		(fp_line
			(start 0.7874 -0.4064)
			(end -0.7874 -0.4064)
			(stroke
				(width 0.1524)
				(type default)
			)
			(layer "B.SilkS")
		)
		(fp_line
			(start -0.67945 0.3048)
			(end -0.120396 0.3048)
			(stroke
				(width 0.1)
				(type default)
			)
			(layer "B.Fab")
		)
		(fp_line
			(start -0.120396 0.3048)
			(end -0.120396 0.2794)
			(stroke
				(width 0.1)
				(type default)
			)
			(layer "B.Fab")
		)
		(fp_line
			(start 0.12065 0.3048)
			(end 0.67945 0.3048)
			(stroke
				(width 0.1)
				(type default)
			)
			(layer "B.Fab")
		)
		(fp_line
			(start 0.67945 0.3048)
			(end 0.67945 -0.305054)
			(stroke
				(width 0.1)
				(type default)
			)
			(layer "B.Fab")
		)
		(fp_line
			(start -0.120396 0.2794)
			(end 0.12065 0.2794)
			(stroke
				(width 0.1)
				(type default)
			)
			(layer "B.Fab")
		)
		(fp_line
			(start 0.12065 0.2794)
			(end 0.12065 0.3048)
			(stroke
				(width 0.1)
				(type default)
			)
			(layer "B.Fab")
		)
		(fp_line
			(start -0.12065 -0.2794)
			(end -0.12065 -0.3048)
			(stroke
				(width 0.1)
				(type default)
			)
			(layer "B.Fab")
		)
		(fp_line
			(start 0.12065 -0.2794)
			(end -0.12065 -0.2794)
			(stroke
				(width 0.1)
				(type default)
			)
			(layer "B.Fab")
		)
		(fp_line
			(start -0.67945 -0.3048)
			(end -0.67945 0.3048)
			(stroke
				(width 0.1)
				(type default)
			)
			(layer "B.Fab")
		)
		(fp_line
			(start -0.12065 -0.3048)
			(end -0.67945 -0.3048)
			(stroke
				(width 0.1)
				(type default)
			)
			(layer "B.Fab")
		)
		(fp_line
			(start 0.12065 -0.305054)
			(end 0.12065 -0.2794)
			(stroke
				(width 0.1)
				(type default)
			)
			(layer "B.Fab")
		)
		(fp_line
			(start 0.67945 -0.305054)
			(end 0.12065 -0.305054)
			(stroke
				(width 0.1)
				(type default)
			)
			(layer "B.Fab")
		)
		(pad "1" smd circle
			(at 0.40005 0 90)
			(size 0 0)
			(layers "B.Cu" "B.Mask" "B.Paste")
			(net "P1V8_PEX")
		)
		(pad "2" smd circle
			(at -0.40005 0 90)
			(size 0 0)
			(layers "B.Cu" "B.Mask" "B.Paste")
			(net "SPI_PEX2_CS_MUX_R_N")
		)
	)
)
